(kicad_pcb
	(version 20260206)
	(generator "pcbnew")
	(generator_version "10.0")
	(general
		(thickness 1.6)
		(legacy_teardrops no)
	)
	(paper "A4")
	(title_block
		(title "Bryce Canyon_IOM_IOC_16318-2_OCP.brd")
		(comment 1 "Bryce Canyon / footprints 1427-1435 of 1605")
	)
	(layers
		(0 "F.Cu" signal "TOP")
		(4 "In1.Cu" signal "L2GND")
		(6 "In2.Cu" signal "L3")
		(8 "In3.Cu" signal "L4VCC")
		(10 "In4.Cu" signal "L5VCC")
		(12 "In5.Cu" signal "L6")
		(14 "In6.Cu" signal "L7GND")
		(2 "B.Cu" signal "BOTTOM")
		(9 "F.Adhes" user "F.Adhesive")
		(11 "B.Adhes" user "B.Adhesive")
		(13 "F.Paste" user "Package Geometry/Pastemask Top")
		(15 "B.Paste" user "Package Geometry/Pastemask Bottom")
		(5 "F.SilkS" user "Ref Des/Silkscreen Top")
		(7 "B.SilkS" user "Ref Des/Silkscreen Bottom")
		(1 "F.Mask" user "Board Geometry/Soldermask Top")
		(3 "B.Mask" user "Board Geometry/Soldermask Bottom")
		(17 "Dwgs.User" user "User.Drawings")
		(19 "Cmts.User" user "User.Comments")
		(21 "Eco1.User" user "User.Eco1")
		(23 "Eco2.User" user "User.Eco2")
		(25 "Edge.Cuts" user "Board Geometry/Outline")
		(27 "Margin" user)
		(31 "F.CrtYd" user "Package Geometry/Place Bound Top")
		(29 "B.CrtYd" user "Package Geometry/Place Bound Bottom")
		(35 "F.Fab" user "Ref Des/Assembly Top")
		(33 "B.Fab" user "Ref Des/Assembly Bottom")
	)
	(footprint ""
		(layer "B.Cu")
		(at 182.5244 -77.2922 -90)
		(property "Reference" "TP94"
			(at 0 0 90)
			(layer "B.SilkS")
			(hide yes)
			(effects
				(font
					(size 1.27 1.27)
				)
				(justify mirror)
			)
		)
		(property "Value" "TPAD28-2-GP"
			(at 0.0127 -1.6637 270)
			(unlocked yes)
			(layer "B.Fab")
			(hide yes)
			(effects
				(font
					(size 1.016 1.016)
					(thickness 0.1524)
				)
				(justify mirror)
			)
		)
		(property "Device Type" "TPAD28"
			(at 0.0127 -3.1877 270)
			(unlocked yes)
			(layer "B.Fab")
			(hide yes)
			(effects
				(font
					(size 1.016 1.016)
					(thickness 0.1524)
				)
				(justify mirror)
			)
		)
		(duplicate_pad_numbers_are_jumpers no)
		(fp_poly
			(pts
				(arc
					(start 0 -0.3556)
					(mid 0 0.3556)
					(end 0 -0.3556)
				)
			)
			(stroke
				(width 0)
				(type default)
			)
			(fill no)
			(layer "B.CrtYd")
		)
		(fp_poly
			(pts
				(arc
					(start 0 -0.6096)
					(mid 0 0.6096)
					(end 0 -0.6096)
				)
			)
			(stroke
				(width 0)
				(type default)
			)
			(fill no)
			(layer "B.Fab")
		)
		(pad "1" smd circle
			(at 0 0 90)
			(size 0.7112 0.7112)
			(layers "B.Cu" "B.Mask" "B.Paste")
			(net "IOC_GPIO_9")
		)
	)
	(footprint ""
		(layer "B.Cu")
		(at 199.089518 -81.153 180)
		(property "Reference" "C293"
			(at 0 0 0)
			(layer "B.SilkS")
			(hide yes)
			(effects
				(font
					(size 1.27 1.27)
				)
				(justify mirror)
			)
		)
		(property "Value" "SCD22U10V1KX-GP"
			(at 2.8321 -1.7399 180)
			(unlocked yes)
			(layer "B.Fab")
			(hide yes)
			(effects
				(font
					(size 1.016 1.016)
					(thickness 0.1524)
				)
				(justify mirror)
			)
		)
		(property "Device Type" "C0201H13"
			(at 2.8321 -3.2639 180)
			(unlocked yes)
			(layer "B.Fab")
			(hide yes)
			(effects
				(font
					(size 1.016 1.016)
					(thickness 0.1524)
				)
				(justify mirror)
			)
		)
		(duplicate_pad_numbers_are_jumpers no)
		(fp_rect
			(start 0.2794 0.6477)
			(end -0.2794 -0.6477)
			(stroke
				(width 0)
				(type default)
			)
			(fill no)
			(layer "B.CrtYd")
		)
		(fp_rect
			(start 0.2794 0.6477)
			(end -0.2794 -0.6477)
			(stroke
				(width 0)
				(type default)
			)
			(fill no)
			(layer "B.Fab")
		)
		(pad "1" smd custom
			(at 0 -0.2794)
			(size 0.0762 0.0762)
			(layers "B.Cu" "B.Mask" "B.Paste")
			(net "PCIE_IOM_TO_COMP_10_DP_C")
			(options
				(clearance outline)
				(anchor circle)
			)
			(primitives
				(gr_poly
					(pts
						(arc
							(start 0.1524 0.127)
							(mid 0.137521 0.162921)
							(end 0.1016 0.1778)
						)
						(arc
							(start -0.1016 0.1778)
							(mid -0.137521 0.162921)
							(end -0.1524 0.127)
						)
						(arc
							(start -0.1524 -0.127)
							(mid -0.137521 -0.162921)
							(end -0.1016 -0.1778)
						)
						(arc
							(start 0.1016 -0.1778)
							(mid 0.137521 -0.162921)
							(end 0.1524 -0.127)
						)
					)
					(width 0)
					(fill yes)
				)
			)
		)
		(pad "2" smd custom
			(at 0 0.2794)
			(size 0.0762 0.0762)
			(layers "B.Cu" "B.Mask" "B.Paste")
			(net "PCIE_IOM_TO_COMP_10_DP")
			(options
				(clearance outline)
				(anchor circle)
			)
			(primitives
				(gr_poly
					(pts
						(arc
							(start 0.1524 0.127)
							(mid 0.137521 0.162921)
							(end 0.1016 0.1778)
						)
						(arc
							(start -0.1016 0.1778)
							(mid -0.137521 0.162921)
							(end -0.1524 0.127)
						)
						(arc
							(start -0.1524 -0.127)
							(mid -0.137521 -0.162921)
							(end -0.1016 -0.1778)
						)
						(arc
							(start 0.1016 -0.1778)
							(mid 0.137521 -0.162921)
							(end 0.1524 -0.127)
						)
					)
					(width 0)
					(fill yes)
				)
			)
		)
	)
	(footprint ""
		(layer "B.Cu")
		(at 203.708 -59.055)
		(property "Reference" "TP115"
			(at 0 0 0)
			(layer "B.SilkS")
			(hide yes)
			(effects
				(font
					(size 1.27 1.27)
				)
				(justify mirror)
			)
		)
		(property "Value" "TPAD28-2-GP"
			(at 0.0127 -1.6637 0)
			(unlocked yes)
			(layer "B.Fab")
			(hide yes)
			(effects
				(font
					(size 1.016 1.016)
					(thickness 0.1524)
				)
				(justify mirror)
			)
		)
		(property "Device Type" "TPAD28"
			(at 0.0127 -3.1877 0)
			(unlocked yes)
			(layer "B.Fab")
			(hide yes)
			(effects
				(font
					(size 1.016 1.016)
					(thickness 0.1524)
				)
				(justify mirror)
			)
		)
		(duplicate_pad_numbers_are_jumpers no)
		(fp_poly
			(pts
				(arc
					(start 0.3556 0)
					(mid -0.3556 0)
					(end 0.3556 0)
				)
			)
			(stroke
				(width 0)
				(type default)
			)
			(fill no)
			(layer "B.CrtYd")
		)
		(fp_poly
			(pts
				(arc
					(start 0.6096 0)
					(mid -0.6096 0)
					(end 0.6096 0)
				)
			)
			(stroke
				(width 0)
				(type default)
			)
			(fill no)
			(layer "B.Fab")
		)
		(pad "1" smd circle
			(at 0 0 180)
			(size 0.7112 0.7112)
			(layers "B.Cu" "B.Mask" "B.Paste")
			(net "SIO_DOUT_0")
		)
	)
	(footprint ""
		(layer "B.Cu")
		(at 125.984 -13.56741)
		(property "Reference" "C144"
			(at 0 0 0)
			(layer "B.SilkS")
			(hide yes)
			(effects
				(font
					(size 1.27 1.27)
				)
				(justify mirror)
			)
		)
		(property "Value" "SC1U16V3KX-5GP"
			(at 0 -2.8194 0)
			(unlocked yes)
			(layer "B.Fab")
			(hide yes)
			(effects
				(font
					(size 1.016 1.016)
					(thickness 0.1524)
				)
				(justify mirror)
			)
		)
		(property "Device Type" "C603H36"
			(at 0 -4.3434 0)
			(unlocked yes)
			(layer "B.Fab")
			(hide yes)
			(effects
				(font
					(size 1.016 1.016)
					(thickness 0.1524)
				)
				(justify mirror)
			)
		)
		(duplicate_pad_numbers_are_jumpers no)
		(fp_line
			(start -0.508 0)
			(end 0.508 0)
			(stroke
				(width 0.2032)
				(type default)
			)
			(layer "B.SilkS")
		)
		(fp_rect
			(start 0.5842 1.3335)
			(end -0.5842 -1.3335)
			(stroke
				(width 0)
				(type default)
			)
			(fill no)
			(layer "B.CrtYd")
		)
		(fp_rect
			(start 0.5842 1.3335)
			(end -0.5842 -1.3335)
			(stroke
				(width 0)
				(type default)
			)
			(fill no)
			(layer "B.Fab")
		)
		(pad "1" smd custom
			(at 0 -0.762 180)
			(size 0.2159 0.2159)
			(layers "B.Cu" "B.Mask" "B.Paste")
			(net "MB0_CM_OV_R")
			(options
				(clearance outline)
				(anchor circle)
			)
			(primitives
				(gr_poly
					(pts
						(arc
							(start -0.3302 0.4318)
							(mid -0.402042 0.402042)
							(end -0.4318 0.3302)
						)
						(arc
							(start -0.4318 -0.3302)
							(mid -0.402042 -0.402042)
							(end -0.3302 -0.4318)
						)
						(arc
							(start 0.3302 -0.4318)
							(mid 0.402042 -0.402042)
							(end 0.4318 -0.3302)
						)
						(arc
							(start 0.4318 0.3302)
							(mid 0.402042 0.402042)
							(end 0.3302 0.4318)
						)
					)
					(width 0)
					(fill yes)
				)
			)
		)
		(pad "2" smd custom
			(at 0 0.762 180)
			(size 0.2159 0.2159)
			(layers "B.Cu" "B.Mask" "B.Paste")
			(net "AGND_CURRENT_MON")
			(options
				(clearance outline)
				(anchor circle)
			)
			(primitives
				(gr_poly
					(pts
						(arc
							(start -0.3302 0.4318)
							(mid -0.402042 0.402042)
							(end -0.4318 0.3302)
						)
						(arc
							(start -0.4318 -0.3302)
							(mid -0.402042 -0.402042)
							(end -0.3302 -0.4318)
						)
						(arc
							(start 0.3302 -0.4318)
							(mid 0.402042 -0.402042)
							(end 0.4318 -0.3302)
						)
						(arc
							(start 0.4318 0.3302)
							(mid 0.402042 0.402042)
							(end 0.3302 0.4318)
						)
					)
					(width 0)
					(fill yes)
				)
			)
		)
	)
	(footprint ""
		(layer "B.Cu")
		(at 79.819246 -56.237378 90)
		(property "Reference" "C187"
			(at 0 0 90)
			(layer "B.SilkS")
			(hide yes)
			(effects
				(font
					(size 1.27 1.27)
				)
				(justify mirror)
			)
		)
		(property "Value" "SC10U6D3V5KX-4GP"
			(at 0.0762 -6.1214 90)
			(unlocked yes)
			(layer "B.Fab")
			(hide yes)
			(effects
				(font
					(size 1.016 1.016)
					(thickness 0.1524)
				)
				(justify mirror)
			)
		)
		(property "Device Type" "C805H58"
			(at 0.0762 -8.1534 90)
			(unlocked yes)
			(layer "B.Fab")
			(hide yes)
			(effects
				(font
					(size 1.016 1.016)
					(thickness 0.1524)
				)
				(justify mirror)
			)
		)
		(duplicate_pad_numbers_are_jumpers no)
		(fp_line
			(start -0.635 0)
			(end 0.635 0)
			(stroke
				(width 0.508)
				(type default)
			)
			(layer "B.SilkS")
		)
		(fp_rect
			(start 0.9652 1.778)
			(end -0.9652 -1.778)
			(stroke
				(width 0)
				(type default)
			)
			(fill no)
			(layer "B.CrtYd")
		)
		(fp_poly
			(pts
				(xy 0.9652 -1.778) (xy -0.9652 -1.778) (xy -0.9652 1.778) (xy 0.9652 1.778)
			)
			(stroke
				(width 0)
				(type default)
			)
			(fill no)
			(layer "B.Fab")
		)
		(pad "1" smd rect
			(at 0 -0.9652 270)
			(size 1.397 1.143)
			(layers "B.Cu" "B.Mask" "B.Paste")
			(net "P3V3")
		)
		(pad "2" smd rect
			(at 0 0.9652 270)
			(size 1.397 1.143)
			(layers "B.Cu" "B.Mask" "B.Paste")
			(net "GND")
		)
	)
	(footprint ""
		(layer "B.Cu")
		(at 181.4576 -68.2244)
		(property "Reference" "TP109"
			(at 0 0 0)
			(layer "B.SilkS")
			(hide yes)
			(effects
				(font
					(size 1.27 1.27)
				)
				(justify mirror)
			)
		)
		(property "Value" "TPAD28-2-GP"
			(at 0.0127 -1.6637 0)
			(unlocked yes)
			(layer "B.Fab")
			(hide yes)
			(effects
				(font
					(size 1.016 1.016)
					(thickness 0.1524)
				)
				(justify mirror)
			)
		)
		(property "Device Type" "TPAD28"
			(at 0.0127 -3.1877 0)
			(unlocked yes)
			(layer "B.Fab")
			(hide yes)
			(effects
				(font
					(size 1.016 1.016)
					(thickness 0.1524)
				)
				(justify mirror)
			)
		)
		(duplicate_pad_numbers_are_jumpers no)
		(fp_poly
			(pts
				(arc
					(start 0.3556 0)
					(mid -0.3556 0)
					(end 0.3556 0)
				)
			)
			(stroke
				(width 0)
				(type default)
			)
			(fill no)
			(layer "B.CrtYd")
		)
		(fp_poly
			(pts
				(arc
					(start 0.6096 0)
					(mid -0.6096 0)
					(end 0.6096 0)
				)
			)
			(stroke
				(width 0)
				(type default)
			)
			(fill no)
			(layer "B.Fab")
		)
		(pad "1" smd circle
			(at 0 0 180)
			(size 0.7112 0.7112)
			(layers "B.Cu" "B.Mask" "B.Paste")
			(net "IOC_GPIO_24")
		)
	)
	(footprint ""
		(layer "B.Cu")
		(at 164.769292 -75.714606)
		(property "Reference" "C328"
			(at 0 0 0)
			(layer "B.SilkS")
			(hide yes)
			(effects
				(font
					(size 1.27 1.27)
				)
				(justify mirror)
			)
		)
		(property "Value" "SCD1U16V2KX-3GP"
			(at -1.1811 -2.7051 0)
			(unlocked yes)
			(layer "B.Fab")
			(hide yes)
			(effects
				(font
					(size 1.016 1.016)
					(thickness 0.1524)
				)
				(justify mirror)
			)
		)
		(property "Device Type" "C402H22"
			(at -1.1811 -4.2291 0)
			(unlocked yes)
			(layer "B.Fab")
			(hide yes)
			(effects
				(font
					(size 1.016 1.016)
					(thickness 0.1524)
				)
				(justify mirror)
			)
		)
		(duplicate_pad_numbers_are_jumpers no)
		(fp_rect
			(start 0.4318 0.9525)
			(end -0.4318 -0.9525)
			(stroke
				(width 0)
				(type default)
			)
			(fill no)
			(layer "B.CrtYd")
		)
		(fp_rect
			(start 0.4318 0.9525)
			(end -0.4318 -0.9525)
			(stroke
				(width 0)
				(type default)
			)
			(fill no)
			(layer "B.Fab")
		)
		(pad "1" smd custom
			(at 0 -0.4445 180)
			(size 0.1524 0.1524)
			(layers "B.Cu" "B.Mask" "B.Paste")
			(net "P1V8")
			(options
				(clearance outline)
				(anchor circle)
			)
			(primitives
				(gr_poly
					(pts
						(arc
							(start 0.3048 0.2032)
							(mid 0.275042 0.275042)
							(end 0.2032 0.3048)
						)
						(arc
							(start -0.2032 0.3048)
							(mid -0.275042 0.275042)
							(end -0.3048 0.2032)
						)
						(arc
							(start -0.3048 -0.2032)
							(mid -0.275042 -0.275042)
							(end -0.2032 -0.3048)
						)
						(arc
							(start 0.2032 -0.3048)
							(mid 0.275042 -0.275042)
							(end 0.3048 -0.2032)
						)
					)
					(width 0)
					(fill yes)
				)
			)
		)
		(pad "2" smd custom
			(at 0 0.4445 180)
			(size 0.1524 0.1524)
			(layers "B.Cu" "B.Mask" "B.Paste")
			(net "GND")
			(options
				(clearance outline)
				(anchor circle)
			)
			(primitives
				(gr_poly
					(pts
						(arc
							(start 0.3048 0.2032)
							(mid 0.275042 0.275042)
							(end 0.2032 0.3048)
						)
						(arc
							(start -0.2032 0.3048)
							(mid -0.275042 0.275042)
							(end -0.3048 0.2032)
						)
						(arc
							(start -0.3048 -0.2032)
							(mid -0.275042 -0.275042)
							(end -0.2032 -0.3048)
						)
						(arc
							(start 0.2032 -0.3048)
							(mid 0.275042 -0.275042)
							(end 0.3048 -0.2032)
						)
					)
					(width 0)
					(fill yes)
				)
			)
		)
	)
	(footprint ""
		(layer "B.Cu")
		(at 177.012346 -154.319732 -90)
		(property "Reference" "C158"
			(at 0 0 90)
			(layer "B.SilkS")
			(hide yes)
			(effects
				(font
					(size 1.27 1.27)
				)
				(justify mirror)
			)
		)
		(property "Value" "SCD1U50V3KX-GP"
			(at 0 -2.8194 270)
			(unlocked yes)
			(layer "B.Fab")
			(hide yes)
			(effects
				(font
					(size 1.016 1.016)
					(thickness 0.1524)
				)
				(justify mirror)
			)
		)
		(property "Device Type" "C603H36"
			(at 0 -4.3434 270)
			(unlocked yes)
			(layer "B.Fab")
			(hide yes)
			(effects
				(font
					(size 1.016 1.016)
					(thickness 0.1524)
				)
				(justify mirror)
			)
		)
		(duplicate_pad_numbers_are_jumpers no)
		(fp_line
			(start -0.508 0)
			(end 0.508 0)
			(stroke
				(width 0.2032)
				(type default)
			)
			(layer "B.SilkS")
		)
		(fp_rect
			(start 0.5842 1.3335)
			(end -0.5842 -1.3335)
			(stroke
				(width 0)
				(type default)
			)
			(fill no)
			(layer "B.CrtYd")
		)
		(fp_rect
			(start 0.5842 1.3335)
			(end -0.5842 -1.3335)
			(stroke
				(width 0)
				(type default)
			)
			(fill no)
			(layer "B.Fab")
		)
		(pad "1" smd custom
			(at 0 -0.762 90)
			(size 0.2159 0.2159)
			(layers "B.Cu" "B.Mask" "B.Paste")
			(net "P5V_VBST_RC")
			(options
				(clearance outline)
				(anchor circle)
			)
			(primitives
				(gr_poly
					(pts
						(arc
							(start -0.3302 0.4318)
							(mid -0.402042 0.402042)
							(end -0.4318 0.3302)
						)
						(arc
							(start -0.4318 -0.3302)
							(mid -0.402042 -0.402042)
							(end -0.3302 -0.4318)
						)
						(arc
							(start 0.3302 -0.4318)
							(mid 0.402042 -0.402042)
							(end 0.4318 -0.3302)
						)
						(arc
							(start 0.4318 0.3302)
							(mid 0.402042 0.402042)
							(end 0.3302 0.4318)
						)
					)
					(width 0)
					(fill yes)
				)
			)
		)
		(pad "2" smd custom
			(at 0 0.762 90)
			(size 0.2159 0.2159)
			(layers "B.Cu" "B.Mask" "B.Paste")
			(net "P5V_LL")
			(options
				(clearance outline)
				(anchor circle)
			)
			(primitives
				(gr_poly
					(pts
						(arc
							(start -0.3302 0.4318)
							(mid -0.402042 0.402042)
							(end -0.4318 0.3302)
						)
						(arc
							(start -0.4318 -0.3302)
							(mid -0.402042 -0.402042)
							(end -0.3302 -0.4318)
						)
						(arc
							(start 0.3302 -0.4318)
							(mid 0.402042 -0.402042)
							(end 0.4318 -0.3302)
						)
						(arc
							(start 0.4318 0.3302)
							(mid 0.402042 0.402042)
							(end 0.3302 0.4318)
						)
					)
					(width 0)
					(fill yes)
				)
			)
		)
	)
	(footprint ""
		(layer "B.Cu")
		(at 88.6968 -161.2646 180)
		(property "Reference" "C15"
			(at 0 0 0)
			(layer "B.SilkS")
			(hide yes)
			(effects
				(font
					(size 1.27 1.27)
				)
				(justify mirror)
			)
		)
		(property "Value" "SC1U16V3KX-5GP"
			(at 0 -2.8194 180)
			(unlocked yes)
			(layer "B.Fab")
			(hide yes)
			(effects
				(font
					(size 1.016 1.016)
					(thickness 0.1524)
				)
				(justify mirror)
			)
		)
		(property "Device Type" "C603H36"
			(at 0 -4.3434 180)
			(unlocked yes)
			(layer "B.Fab")
			(hide yes)
			(effects
				(font
					(size 1.016 1.016)
					(thickness 0.1524)
				)
				(justify mirror)
			)
		)
		(duplicate_pad_numbers_are_jumpers no)
		(fp_line
			(start -0.508 0)
			(end 0.508 0)
			(stroke
				(width 0.2032)
				(type default)
			)
			(layer "B.SilkS")
		)
		(fp_rect
			(start 0.5842 1.3335)
			(end -0.5842 -1.3335)
			(stroke
				(width 0)
				(type default)
			)
			(fill no)
			(layer "B.CrtYd")
		)
		(fp_rect
			(start 0.5842 1.3335)
			(end -0.5842 -1.3335)
			(stroke
				(width 0)
				(type default)
			)
			(fill no)
			(layer "B.Fab")
		)
		(pad "1" smd custom
			(at 0 -0.762)
			(size 0.2159 0.2159)
			(layers "B.Cu" "B.Mask" "B.Paste")
			(net "P3V3_STBY")
			(options
				(clearance outline)
				(anchor circle)
			)
			(primitives
				(gr_poly
					(pts
						(arc
							(start -0.3302 0.4318)
							(mid -0.402042 0.402042)
							(end -0.4318 0.3302)
						)
						(arc
							(start -0.4318 -0.3302)
							(mid -0.402042 -0.402042)
							(end -0.3302 -0.4318)
						)
						(arc
							(start 0.3302 -0.4318)
							(mid 0.402042 -0.402042)
							(end 0.4318 -0.3302)
						)
						(arc
							(start 0.4318 0.3302)
							(mid 0.402042 0.402042)
							(end 0.3302 0.4318)
						)
					)
					(width 0)
					(fill yes)
				)
			)
		)
		(pad "2" smd custom
			(at 0 0.762)
			(size 0.2159 0.2159)
			(layers "B.Cu" "B.Mask" "B.Paste")
			(net "GND")
			(options
				(clearance outline)
				(anchor circle)
			)
			(primitives
				(gr_poly
					(pts
						(arc
							(start -0.3302 0.4318)
							(mid -0.402042 0.402042)
							(end -0.4318 0.3302)
						)
						(arc
							(start -0.4318 -0.3302)
							(mid -0.402042 -0.402042)
							(end -0.3302 -0.4318)
						)
						(arc
							(start 0.3302 -0.4318)
							(mid 0.402042 -0.402042)
							(end 0.4318 -0.3302)
						)
						(arc
							(start 0.4318 0.3302)
							(mid 0.402042 0.402042)
							(end 0.3302 0.4318)
						)
					)
					(width 0)
					(fill yes)
				)
			)
		)
	)
)
